(kicad_pcb
	(version 20221018)
	(generator pcbnew)
	(general
    (thickness 1.62)
  )
	(paper "A4")
	(title_block
    (title "ECP5 - Datacenter Secure Control Module (DC-SCM)")
    (date "2024-07-01")
    (rev "1.2.1")
		(comment 9 "footprints 80-80 of 506")
	)
	(layers
    (0 "F.Cu" signal)
    (1 "In1.Cu" power)
    (2 "In2.Cu" signal)
    (3 "In3.Cu" power)
    (4 "In4.Cu" power)
    (5 "In5.Cu" signal)
    (6 "In6.Cu" power)
    (31 "B.Cu" signal)
    (32 "B.Adhes" user "B.Adhesive")
    (33 "F.Adhes" user "F.Adhesive")
    (34 "B.Paste" user)
    (35 "F.Paste" user)
    (36 "B.SilkS" user "B.Silkscreen")
    (37 "F.SilkS" user "F.Silkscreen")
    (38 "B.Mask" user)
    (39 "F.Mask" user)
    (40 "Dwgs.User" user "User.Drawings")
    (41 "Cmts.User" user "User.Comments")
    (42 "Eco1.User" user "User.Eco1")
    (43 "Eco2.User" user "User.Eco2")
    (44 "Edge.Cuts" user)
    (45 "Margin" user)
    (46 "B.CrtYd" user "B.Courtyard")
    (47 "F.CrtYd" user "F.Courtyard")
    (48 "B.Fab" user)
    (49 "F.Fab" user)
  )
	(footprint "antmicro-footprints:Bus_M.2_Socket_Key_M_TE_1-2199230-6" locked (layer "F.Cu")
    (at 129.545 161.1145 180)
    (property "Author" "Antmicro")
    (property "License" "Apache-2.0")
    (property "MPN" "1-2199230-6")
    (property "Manufacturer" "TE Connectivity")
    (property "Sheetfile" "pcie-conn.kicad_sch")
    (property "Sheetname" "PCIe-connector")
    (property "ki_description" "Key M Card Edge Connector, 0, Dual Side, 67 Contacts, Surface Mount, Right Angle, Solder")
    (property "ki_keywords" "HORIZONTAL, SMT, PCIE, CONNECTOR")
    (attr smd)
    (fp_text reference "J2" (at 12.06 3.2) (layer "F.SilkS")
        (effects (font (size 0.7 0.7) (thickness 0.127)))
    )
    (fp_text value "Bus_M.2_1-2199230-6" (at 2.99206 4.516565) (layer "F.Fab")
        (effects (font (size 1.40848 1.40848) (thickness 0.015)))
    )
    (fp_text user "Author: Antmicro" (at -11.35 9.325 180) (layer "F.Fab") hide
        (effects (font (size 0.7 0.7) (thickness 0.15)) (justify left bottom))
    )
    (fp_text user "${REFERENCE}" (at -11.35 8.124 180) (layer "F.Fab") hide
        (effects (font (size 0.7 0.7) (thickness 0.15)) (justify left bottom))
    )
    (fp_text user "License: Apache-2.0" (at -11.35 10.525 180) (layer "F.Fab") hide
        (effects (font (size 0.7 0.7) (thickness 0.15)) (justify left bottom))
    )
    (fp_line (start -10.951 -1.401) (end -10.951 0.55)
      (stroke (width 0.15) (type solid)) (layer "F.SilkS"))
    (fp_line (start -10.951 2.7) (end -10.951 3.999)
      (stroke (width 0.15) (type solid)) (layer "F.SilkS"))
    (fp_line (start -10.951 3.999) (end -9.352 3.999)
      (stroke (width 0.15) (type solid)) (layer "F.SilkS"))
    (fp_line (start 5.097 -3.75) (end 6.898 -3.75)
      (stroke (width 0.15) (type solid)) (layer "F.SilkS"))
    (fp_line (start 5.347 3.999) (end 7.148 3.999)
      (stroke (width 0.15) (type solid)) (layer "F.SilkS"))
    (fp_line (start 9.448 3.999) (end 10.948 3.999)
      (stroke (width 0.15) (type solid)) (layer "F.SilkS"))
    (fp_line (start 10.948 0.449) (end 10.948 -1.301)
      (stroke (width 0.15) (type solid)) (layer "F.SilkS"))
    (fp_line (start 10.948 3.999) (end 10.948 2.3)
      (stroke (width 0.15) (type solid)) (layer "F.SilkS"))
    (fp_circle (center -9.25 -5.651) (end -9.2 -5.651)
      (stroke (width 0.15) (type solid)) (fill solid) (layer "F.SilkS"))
    (fp_circle (center -9.25 -4.875) (end -9.201 -4.826)
      (stroke (width 0.15) (type solid)) (fill solid) (layer "F.SilkS"))
    (fp_line (start -11.16 -4.83) (end -11.16 4.78)
      (stroke (width 0.05) (type solid)) (layer "F.CrtYd"))
    (fp_line (start -11.16 4.78) (end 11.15 4.78)
      (stroke (width 0.05) (type solid)) (layer "F.CrtYd"))
    (fp_line (start 11.15 -4.83) (end -11.16 -4.83)
      (stroke (width 0.05) (type solid)) (layer "F.CrtYd"))
    (fp_line (start 11.15 4.78) (end 11.15 -4.83)
      (stroke (width 0.05) (type solid)) (layer "F.CrtYd"))
    (fp_line (start -10.949 -3.55) (end -10.4 -4.1)
      (stroke (width 0.15) (type solid)) (layer "F.Fab"))
    (fp_line (start -10.949 4.2) (end -10.949 -3.55)
      (stroke (width 0.15) (type solid)) (layer "F.Fab"))
    (fp_line (start -10.4 -4.1) (end 10.95 -4.1)
      (stroke (width 0.15) (type solid)) (layer "F.Fab"))
    (fp_line (start 10.95 -4.1) (end 10.95 4.2)
      (stroke (width 0.15) (type solid)) (layer "F.Fab"))
    (fp_line (start 10.95 4.2) (end -10.949 4.2)
      (stroke (width 0.15) (type solid)) (layer "F.Fab"))
    (pad "" np_thru_hole circle locked (at -10 1.499 180) (size 1.1 1.1) (drill 1.1) (layers "*.Mask"))
    (pad "" np_thru_hole circle locked (at 9.997 1.499 180) (size 1.6 1.6) (drill 1.6) (layers "*.Mask"))
    (pad "1" smd rect locked (at -9.25 -3.775 180) (size 0.3 1.55) (layers "F.Cu" "F.Paste" "F.Mask")
      (net 1 "GND") (pinfunction "GND") (pintype "power_in"))
    (pad "2" smd rect locked (at -9.003 3.773 180) (size 0.3 1.55) (layers "F.Cu" "F.Paste" "F.Mask")
      (net 2 "VCC3V3") (pinfunction "3V3") (pintype "passive"))
    (pad "3" smd rect locked (at -8.753 -3.775 180) (size 0.3 1.55) (layers "F.Cu" "F.Paste" "F.Mask")
      (net 1 "GND") (pinfunction "GND") (pintype "passive"))
    (pad "4" smd rect locked (at -8.503 3.773 180) (size 0.3 1.55) (layers "F.Cu" "F.Paste" "F.Mask")
      (net 2 "VCC3V3") (pinfunction "3V3") (pintype "passive"))
    (pad "5" smd rect locked (at -8.253 -3.775 180) (size 0.3 1.55) (layers "F.Cu" "F.Paste" "F.Mask")
      (net 696 "PCIE_HPM_RX3_N") (pinfunction "PER3_N") (pintype "output"))
    (pad "6" smd rect locked (at -8.001 3.773 180) (size 0.3 1.55) (layers "F.Cu" "F.Paste" "F.Mask")
      (net 351 "unconnected-(J2-NC-Pad6)") (pinfunction "NC") (pintype "no_connect"))
    (pad "7" smd rect locked (at -7.752 -3.775 180) (size 0.3 1.55) (layers "F.Cu" "F.Paste" "F.Mask")
      (net 697 "PCIE_HPM_RX3_P") (pinfunction "PER3_P") (pintype "output"))
    (pad "8" smd rect locked (at -7.502 3.773 180) (size 0.3 1.55) (layers "F.Cu" "F.Paste" "F.Mask")
      (net 353 "unconnected-(J2-NC-Pad8)") (pinfunction "NC") (pintype "no_connect"))
    (pad "9" smd rect locked (at -7.252 -3.775 180) (size 0.3 1.55) (layers "F.Cu" "F.Paste" "F.Mask")
      (net 1 "GND") (pinfunction "GND") (pintype "passive"))
    (pad "10" smd rect locked (at -7.002 3.773 180) (size 0.3 1.55) (layers "F.Cu" "F.Paste" "F.Mask")
      (net 308 "Net-(D1-C)") (pinfunction "LED") (pintype "passive"))
    (pad "11" smd rect locked (at -6.752 -3.775 180) (size 0.3 1.55) (layers "F.Cu" "F.Paste" "F.Mask")
      (net 216 "Net-(J2-PET3_N)") (pinfunction "PET3_N") (pintype "input"))
    (pad "12" smd rect locked (at -6.502 3.773 180) (size 0.3 1.55) (layers "F.Cu" "F.Paste" "F.Mask")
      (net 2 "VCC3V3") (pinfunction "3V3") (pintype "passive"))
    (pad "13" smd rect locked (at -6.252 -3.775 180) (size 0.3 1.55) (layers "F.Cu" "F.Paste" "F.Mask")
      (net 212 "Net-(J2-PET3_P)") (pinfunction "PET3_P") (pintype "input"))
    (pad "14" smd rect locked (at -6.002 3.773 180) (size 0.3 1.55) (layers "F.Cu" "F.Paste" "F.Mask")
      (net 2 "VCC3V3") (pinfunction "3V3") (pintype "passive"))
    (pad "15" smd rect locked (at -5.752 -3.775 180) (size 0.3 1.55) (layers "F.Cu" "F.Paste" "F.Mask")
      (net 1 "GND") (pinfunction "GND") (pintype "passive"))
    (pad "16" smd rect locked (at -5.502 3.773 180) (size 0.3 1.55) (layers "F.Cu" "F.Paste" "F.Mask")
      (net 2 "VCC3V3") (pinfunction "3V3") (pintype "passive"))
    (pad "17" smd rect locked (at -5.252 -3.775 180) (size 0.3 1.55) (layers "F.Cu" "F.Paste" "F.Mask")
      (net 698 "PCIE_HPM_RX2_N") (pinfunction "PER2_N") (pintype "output"))
    (pad "18" smd rect locked (at -5.002 3.773 180) (size 0.3 1.55) (layers "F.Cu" "F.Paste" "F.Mask")
      (net 2 "VCC3V3") (pinfunction "3V3") (pintype "passive"))
    (pad "19" smd rect locked (at -4.752 -3.775 180) (size 0.3 1.55) (layers "F.Cu" "F.Paste" "F.Mask")
      (net 699 "PCIE_HPM_RX2_P") (pinfunction "PER2_P") (pintype "output"))
    (pad "20" smd rect locked (at -4.502 3.773 180) (size 0.3 1.55) (layers "F.Cu" "F.Paste" "F.Mask")
      (net 360 "unconnected-(J2-NC-Pad20)") (pinfunction "NC") (pintype "no_connect"))
    (pad "21" smd rect locked (at -4.252 -3.775 180) (size 0.3 1.55) (layers "F.Cu" "F.Paste" "F.Mask")
      (net 1 "GND") (pinfunction "GND") (pintype "passive"))
    (pad "22" smd rect locked (at -4.002 3.773 180) (size 0.3 1.55) (layers "F.Cu" "F.Paste" "F.Mask")
      (net 361 "unconnected-(J2-NC-Pad22)") (pinfunction "NC") (pintype "no_connect"))
    (pad "23" smd rect locked (at -3.751 -3.775 180) (size 0.3 1.55) (layers "F.Cu" "F.Paste" "F.Mask")
      (net 215 "Net-(J2-PET2_N)") (pinfunction "PET2_N") (pintype "input"))
    (pad "24" smd rect locked (at -3.501 3.773 180) (size 0.3 1.55) (layers "F.Cu" "F.Paste" "F.Mask")
      (net 362 "unconnected-(J2-NC-Pad24)") (pinfunction "NC") (pintype "no_connect"))
    (pad "25" smd rect locked (at -3.251 -3.775 180) (size 0.3 1.55) (layers "F.Cu" "F.Paste" "F.Mask")
      (net 18 "Net-(J2-PET2_P)") (pinfunction "PET2_P") (pintype "input"))
    (pad "26" smd rect locked (at -3.001 3.773 180) (size 0.3 1.55) (layers "F.Cu" "F.Paste" "F.Mask")
      (net 363 "unconnected-(J2-NC-Pad26)") (pinfunction "NC") (pintype "no_connect"))
    (pad "27" smd rect locked (at -2.751 -3.775 180) (size 0.3 1.55) (layers "F.Cu" "F.Paste" "F.Mask")
      (net 1 "GND") (pinfunction "GND") (pintype "passive"))
    (pad "28" smd rect locked (at -2.501 3.773 180) (size 0.3 1.55) (layers "F.Cu" "F.Paste" "F.Mask")
      (net 365 "unconnected-(J2-NC-Pad28)") (pinfunction "NC") (pintype "no_connect"))
    (pad "29" smd rect locked (at -2.251 -3.775 180) (size 0.3 1.55) (layers "F.Cu" "F.Paste" "F.Mask")
      (net 700 "PCIE_HPM_RX1_N") (pinfunction "PER1_N") (pintype "output"))
    (pad "30" smd rect locked (at -2.001 3.773 180) (size 0.3 1.55) (layers "F.Cu" "F.Paste" "F.Mask")
      (net 369 "unconnected-(J2-NC-Pad30)") (pinfunction "NC") (pintype "no_connect"))
    (pad "31" smd rect locked (at -1.752 -3.775 180) (size 0.3 1.55) (layers "F.Cu" "F.Paste" "F.Mask")
      (net 701 "PCIE_HPM_RX1_P") (pinfunction "PER1_P") (pintype "output"))
    (pad "32" smd rect locked (at -1.502 3.773 180) (size 0.3 1.55) (layers "F.Cu" "F.Paste" "F.Mask")
      (net 370 "unconnected-(J2-NC-Pad32)") (pinfunction "NC") (pintype "no_connect"))
    (pad "33" smd rect locked (at -1.252 -3.775 180) (size 0.3 1.55) (layers "F.Cu" "F.Paste" "F.Mask")
      (net 1 "GND") (pinfunction "GND") (pintype "passive"))
    (pad "34" smd rect locked (at -1.002 3.773 180) (size 0.3 1.55) (layers "F.Cu" "F.Paste" "F.Mask")
      (net 371 "unconnected-(J2-NC-Pad34)") (pinfunction "NC") (pintype "no_connect"))
    (pad "35" smd rect locked (at -0.751 -3.775 180) (size 0.3 1.55) (layers "F.Cu" "F.Paste" "F.Mask")
      (net 214 "Net-(J2-PET1_N)") (pinfunction "PET1_N") (pintype "input"))
    (pad "36" smd rect locked (at -0.501 3.773 180) (size 0.3 1.55) (layers "F.Cu" "F.Paste" "F.Mask")
      (net 372 "unconnected-(J2-NC-Pad36)") (pinfunction "NC") (pintype "no_connect"))
    (pad "37" smd rect locked (at -0.251 -3.775 180) (size 0.3 1.55) (layers "F.Cu" "F.Paste" "F.Mask")
      (net 17 "Net-(J2-PET1_P)") (pinfunction "PET1_P") (pintype "input"))
    (pad "38" smd rect locked (at -0.001 3.773 180) (size 0.3 1.55) (layers "F.Cu" "F.Paste" "F.Mask")
      (net 373 "unconnected-(J2-NC-Pad38)") (pinfunction "NC") (pintype "no_connect"))
    (pad "39" smd rect locked (at 0.248 -3.775 180) (size 0.3 1.55) (layers "F.Cu" "F.Paste" "F.Mask")
      (net 1 "GND") (pinfunction "GND") (pintype "passive"))
    (pad "40" smd rect locked (at 0.498 3.773 180) (size 0.3 1.55) (layers "F.Cu" "F.Paste" "F.Mask")
      (net 374 "unconnected-(J2-SMB_CLK-Pad40)") (pinfunction "SMB_CLK") (pintype "input+no_connect"))
    (pad "41" smd rect locked (at 0.748 -3.775 180) (size 0.3 1.55) (layers "F.Cu" "F.Paste" "F.Mask")
      (net 703 "PCIE_HPM_RX0_N") (pinfunction "PER0_N") (pintype "output"))
    (pad "42" smd rect locked (at 0.998 3.773 180) (size 0.3 1.55) (layers "F.Cu" "F.Paste" "F.Mask")
      (net 375 "unconnected-(J2-SMB_DATA-Pad42)") (pinfunction "SMB_DATA") (pintype "bidirectional+no_connect"))
    (pad "43" smd rect locked (at 1.249 -3.775 180) (size 0.3 1.55) (layers "F.Cu" "F.Paste" "F.Mask")
      (net 702 "PCIE_HPM_RX0_P") (pinfunction "PER0_P") (pintype "output"))
    (pad "44" smd rect locked (at 1.499 3.773 180) (size 0.3 1.55) (layers "F.Cu" "F.Paste" "F.Mask")
      (net 376 "Net-(J2-ALERT)") (pinfunction "ALERT") (pintype "output"))
    (pad "45" smd rect locked (at 1.749 -3.775 180) (size 0.3 1.55) (layers "F.Cu" "F.Paste" "F.Mask")
      (net 1 "GND") (pinfunction "GND") (pintype "passive"))
    (pad "46" smd rect locked (at 1.999 3.773 180) (size 0.3 1.55) (layers "F.Cu" "F.Paste" "F.Mask")
      (net 378 "unconnected-(J2-NC-Pad46)") (pinfunction "NC") (pintype "no_connect"))
    (pad "47" smd rect locked (at 2.249 -3.775 180) (size 0.3 1.55) (layers "F.Cu" "F.Paste" "F.Mask")
      (net 213 "Net-(J2-PET0_N)") (pinfunction "PET0_N") (pintype "input"))
    (pad "48" smd rect locked (at 2.499 3.773 180) (size 0.3 1.55) (layers "F.Cu" "F.Paste" "F.Mask")
      (net 379 "unconnected-(J2-NC-Pad48)") (pinfunction "NC") (pintype "no_connect"))
    (pad "49" smd rect locked (at 2.749 -3.775 180) (size 0.3 1.55) (layers "F.Cu" "F.Paste" "F.Mask")
      (net 16 "Net-(J2-PET0_P)") (pinfunction "PET0_P") (pintype "input"))
    (pad "50" smd rect locked (at 2.999 3.773 180) (size 0.3 1.55) (layers "F.Cu" "F.Paste" "F.Mask")
      (net 58 "PRSNT0_N") (pinfunction "~{PERST}") (pintype "input"))
    (pad "51" smd rect locked (at 3.249 -3.775 180) (size 0.3 1.55) (layers "F.Cu" "F.Paste" "F.Mask")
      (net 1 "GND") (pinfunction "GND") (pintype "passive"))
    (pad "52" smd rect locked (at 3.499 3.773 180) (size 0.3 1.55) (layers "F.Cu" "F.Paste" "F.Mask")
      (net 380 "Net-(J2-~{CLKREQ})") (pinfunction "~{CLKREQ}") (pintype "output"))
    (pad "53" smd rect locked (at 3.749 -3.775 180) (size 0.3 1.55) (layers "F.Cu" "F.Paste" "F.Mask")
      (net 266 "CLK_PCIE_x4_DN") (pinfunction "REFCLK_N") (pintype "input"))
    (pad "54" smd rect locked (at 3.999 3.773 180) (size 0.3 1.55) (layers "F.Cu" "F.Paste" "F.Mask")
      (net 381 "Net-(J2-~{PEWAKE})") (pinfunction "~{PEWAKE}") (pintype "input"))
    (pad "55" smd rect locked (at 4.248 -3.775 180) (size 0.3 1.55) (layers "F.Cu" "F.Paste" "F.Mask")
      (net 264 "CLK_PCIE_x4_DP") (pinfunction "REFCLK_P") (pintype "input"))
    (pad "56" smd rect locked (at 4.498 3.773 180) (size 0.3 1.55) (layers "F.Cu" "F.Paste" "F.Mask")
      (net 382 "unconnected-(J2-NC-Pad56)") (pinfunction "NC") (pintype "no_connect"))
    (pad "57" smd rect locked (at 4.748 -3.775 180) (size 0.3 1.55) (layers "F.Cu" "F.Paste" "F.Mask")
      (net 1 "GND") (pinfunction "GND") (pintype "passive"))
    (pad "58" smd rect locked (at 4.998 3.773 180) (size 0.3 1.55) (layers "F.Cu" "F.Paste" "F.Mask")
      (net 383 "unconnected-(J2-NC-Pad58)") (pinfunction "NC") (pintype "no_connect"))
    (pad "67" smd rect locked (at 7.248 -3.775 180) (size 0.3 1.55) (layers "F.Cu" "F.Paste" "F.Mask")
      (net 384 "unconnected-(J2-NC-Pad67)") (pinfunction "NC") (pintype "no_connect"))
    (pad "68" smd rect locked (at 7.498 3.773 180) (size 0.3 1.55) (layers "F.Cu" "F.Paste" "F.Mask")
      (net 386 "unconnected-(J2-SUSCLK-Pad68)") (pinfunction "SUSCLK") (pintype "input+no_connect"))
    (pad "69" smd rect locked (at 7.748 -3.775 180) (size 0.3 1.55) (layers "F.Cu" "F.Paste" "F.Mask")
      (net 387 "unconnected-(J2-NC-Pad69)") (pinfunction "NC") (pintype "no_connect"))
    (pad "70" smd rect locked (at 7.998 3.773 180) (size 0.3 1.55) (layers "F.Cu" "F.Paste" "F.Mask")
      (net 2 "VCC3V3") (pinfunction "3V3") (pintype "passive"))
    (pad "71" smd rect locked (at 8.247 -3.775 180) (size 0.3 1.55) (layers "F.Cu" "F.Paste" "F.Mask")
      (net 1 "GND") (pinfunction "GND") (pintype "passive"))
    (pad "72" smd rect locked (at 8.497 3.773 180) (size 0.3 1.55) (layers "F.Cu" "F.Paste" "F.Mask")
      (net 2 "VCC3V3") (pinfunction "3V3") (pintype "passive"))
    (pad "73" smd rect locked (at 8.747 -3.775 180) (size 0.3 1.55) (layers "F.Cu" "F.Paste" "F.Mask")
      (net 1 "GND") (pinfunction "GND") (pintype "passive"))
    (pad "74" smd rect locked (at 8.997 3.773 180) (size 0.3 1.55) (layers "F.Cu" "F.Paste" "F.Mask")
      (net 2 "VCC3V3") (pinfunction "3V3") (pintype "passive"))
    (pad "75" smd rect locked (at 9.247 -3.775 180) (size 0.3 1.55) (layers "F.Cu" "F.Paste" "F.Mask")
      (net 1 "GND") (pinfunction "GND") (pintype "passive"))
    (pad "MP1" smd rect locked (at -10.352 -3 180) (size 1.2 2.75) (layers "F.Cu" "F.Paste" "F.Mask")
      (net 1 "GND") (pinfunction "MP") (pintype "passive"))
    (pad "MP2" smd rect locked (at 10.349 -3 180) (size 1.2 2.75) (layers "F.Cu" "F.Paste" "F.Mask")
      (net 1 "GND") (pinfunction "MP") (pintype "passive"))
  )
)
